# S9S_MB_2U (Grand Teton) — schematic netlist excerpt (pin names and nets, part order shuffled) for the footprints in the layout excerpt that follows; sources: Cadence DE-HDL packaged netlist, KiCad conversion of 03242023_DA0F0TMBIJ0_F0T_Motherboard_J_brd_V01_OCP.brd

R219  Q_RES  100 1% CHIP  pkg 0402LF  page 122 : A = PVNN_TERM_CPU0 ; B = H_CPU0_MEMHOT_IN_LVC1_R1_N
C933  Q_CAP_DIFFBUS  DIFF BUS_0.22UF 6.3V 20% X6S  pkg C0201  page 173 : \1\ = P5E_CPU0_PE0_TX_C_DP<0> ; \2\ = P5E_CPU0_PE0_TX_DP<0>
PC480  Q_CAP  2.2UF 10V 10% X6S  pkg C0402  page 288 : A = PVCCIN_CPU1_VDD7 ; B = GND

(kicad_pcb
	(version 20260206)
	(generator "pcbnew")
	(generator_version "10.0")
	(general
		(thickness 1.6)
		(legacy_teardrops no)
	)
	(paper "A4")
	(title_block
		(title "03242023_DA0F0TMBIJ0_F0T_Motherboard_J_brd_V01_OCP.brd")
		(comment 1 "Grand Teton / footprints 3517-3519 of 6105")
	)
	(layers
		(0 "F.Cu" signal "TOP")
		(4 "In1.Cu" signal "GND")
		(6 "In2.Cu" signal "IN1")
		(8 "In3.Cu" signal "GND1")
		(10 "In4.Cu" signal "IN2")
		(12 "In5.Cu" signal "GND2")
		(14 "In6.Cu" signal "IN3")
		(16 "In7.Cu" signal "GND3")
		(18 "In8.Cu" signal "VCC")
		(20 "In9.Cu" signal "VCC1")
		(22 "In10.Cu" signal "GND4")
		(24 "In11.Cu" signal "IN4")
		(26 "In12.Cu" signal "GND5")
		(28 "In13.Cu" signal "IN5")
		(30 "In14.Cu" signal "GND6")
		(32 "In15.Cu" signal "IN6")
		(34 "In16.Cu" signal "GND7")
		(2 "B.Cu" signal "BOTTOM")
		(9 "F.Adhes" user "F.Adhesive")
		(11 "B.Adhes" user "B.Adhesive")
		(13 "F.Paste" user "Package Geometry/Pastemask Top")
		(15 "B.Paste" user "Package Geometry/Pastemask Bottom")
		(5 "F.SilkS" user "Ref Des/Silkscreen Top")
		(7 "B.SilkS" user "Ref Des/Silkscreen Bottom")
		(1 "F.Mask" user "Board Geometry/Soldermask Top")
		(3 "B.Mask" user "Board Geometry/Soldermask Bottom")
		(17 "Dwgs.User" user "User.Drawings")
		(19 "Cmts.User" user "User.Comments")
		(21 "Eco1.User" user "User.Eco1")
		(23 "Eco2.User" user "User.Eco2")
		(25 "Edge.Cuts" user "Board Geometry/Outline")
		(27 "Margin" user)
		(31 "F.CrtYd" user "Package Geometry/Place Bound Top")
		(29 "B.CrtYd" user "Package Geometry/Place Bound Bottom")
		(35 "F.Fab" user "Ref Des/Assembly Top")
		(33 "B.Fab" user "Ref Des/Assembly Bottom")
	)
	(footprint ""
		(layer "F.Cu")
		(at 352.163888 -408.517344 -90)
		(property "Reference" "C933"
			(at 0 0 270)
			(layer "F.SilkS")
			(hide yes)
			(effects
				(font
					(size 1.27 1.27)
				)
			)
		)
		(property "Value" ""
			(at 0 0 270)
			(layer "F.Fab")
			(effects
				(font
					(size 1.27 1.27)
				)
			)
		)
		(duplicate_pad_numbers_are_jumpers no)
		(fp_line
			(start -0.299974 0.150114)
			(end -0.299974 -0.150114)
			(stroke
				(width 0.1)
				(type default)
			)
			(layer "F.Fab")
		)
		(fp_line
			(start 0.299974 0.150114)
			(end -0.299974 0.150114)
			(stroke
				(width 0.1)
				(type default)
			)
			(layer "F.Fab")
		)
		(fp_line
			(start -0.299974 -0.150114)
			(end 0.299974 -0.150114)
			(stroke
				(width 0.1)
				(type default)
			)
			(layer "F.Fab")
		)
		(fp_line
			(start 0.299974 -0.150114)
			(end 0.299974 0.150114)
			(stroke
				(width 0.1)
				(type default)
			)
			(layer "F.Fab")
		)
		(pad "1" smd rect
			(at -0.2667 0 270)
			(size 0.3048 0.381)
			(layers "F.Cu" "F.Mask" "F.Paste")
			(net "P5E_CPU0_PE0_TX_C_DP<0>")
		)
		(pad "2" smd rect
			(at 0.2667 0 270)
			(size 0.3048 0.381)
			(layers "F.Cu" "F.Mask" "F.Paste")
			(net "P5E_CPU0_PE0_TX_DP<0>")
		)
	)
	(footprint ""
		(layer "F.Cu")
		(at 181.15788 -97.119948 90)
		(property "Reference" "R219"
			(at 0 0 90)
			(layer "F.SilkS")
			(hide yes)
			(effects
				(font
					(size 1.27 1.27)
				)
			)
		)
		(property "Value" ""
			(at 0 0 90)
			(layer "F.Fab")
			(effects
				(font
					(size 1.27 1.27)
				)
			)
		)
		(duplicate_pad_numbers_are_jumpers no)
		(fp_line
			(start 0.7874 -0.4064)
			(end 0.7874 0.4064)
			(stroke
				(width 0.1524)
				(type default)
			)
			(layer "F.SilkS")
		)
		(fp_line
			(start -0.7874 -0.4064)
			(end 0.7874 -0.4064)
			(stroke
				(width 0.1524)
				(type default)
			)
			(layer "F.SilkS")
		)
		(fp_line
			(start 0.7874 0.4064)
			(end -0.7874 0.4064)
			(stroke
				(width 0.1524)
				(type default)
			)
			(layer "F.SilkS")
		)
		(fp_line
			(start -0.7874 0.4064)
			(end -0.7874 -0.4064)
			(stroke
				(width 0.1524)
				(type default)
			)
			(layer "F.SilkS")
		)
		(fp_line
			(start -0.12065 -0.305054)
			(end -0.12065 -0.2794)
			(stroke
				(width 0.1)
				(type default)
			)
			(layer "F.Fab")
		)
		(fp_line
			(start -0.67945 -0.305054)
			(end -0.12065 -0.305054)
			(stroke
				(width 0.1)
				(type default)
			)
			(layer "F.Fab")
		)
		(fp_line
			(start 0.67945 -0.3048)
			(end 0.67945 0.3048)
			(stroke
				(width 0.1)
				(type default)
			)
			(layer "F.Fab")
		)
		(fp_line
			(start 0.12065 -0.3048)
			(end 0.67945 -0.3048)
			(stroke
				(width 0.1)
				(type default)
			)
			(layer "F.Fab")
		)
		(fp_line
			(start 0.12065 -0.2794)
			(end 0.12065 -0.3048)
			(stroke
				(width 0.1)
				(type default)
			)
			(layer "F.Fab")
		)
		(fp_line
			(start -0.12065 -0.2794)
			(end 0.12065 -0.2794)
			(stroke
				(width 0.1)
				(type default)
			)
			(layer "F.Fab")
		)
		(fp_line
			(start 0.120396 0.2794)
			(end -0.12065 0.2794)
			(stroke
				(width 0.1)
				(type default)
			)
			(layer "F.Fab")
		)
		(fp_line
			(start -0.12065 0.2794)
			(end -0.12065 0.3048)
			(stroke
				(width 0.1)
				(type default)
			)
			(layer "F.Fab")
		)
		(fp_line
			(start 0.67945 0.3048)
			(end 0.120396 0.3048)
			(stroke
				(width 0.1)
				(type default)
			)
			(layer "F.Fab")
		)
		(fp_line
			(start 0.120396 0.3048)
			(end 0.120396 0.2794)
			(stroke
				(width 0.1)
				(type default)
			)
			(layer "F.Fab")
		)
		(fp_line
			(start -0.12065 0.3048)
			(end -0.67945 0.3048)
			(stroke
				(width 0.1)
				(type default)
			)
			(layer "F.Fab")
		)
		(fp_line
			(start -0.67945 0.3048)
			(end -0.67945 -0.305054)
			(stroke
				(width 0.1)
				(type default)
			)
			(layer "F.Fab")
		)
		(pad "1" smd circle
			(at -0.40005 0 90)
			(size 0 0)
			(layers "F.Cu" "F.Mask" "F.Paste")
			(net "PVNN_TERM_CPU0")
		)
		(pad "2" smd circle
			(at 0.40005 0 90)
			(size 0 0)
			(layers "F.Cu" "F.Mask" "F.Paste")
			(net "H_CPU0_MEMHOT_IN_LVC1_R1_N")
		)
	)
	(footprint ""
		(layer "F.Cu")
		(at 77.107542 -345.402662 90)
		(property "Reference" "PC480"
			(at 0 0 90)
			(layer "F.SilkS")
			(hide yes)
			(effects
				(font
					(size 1.27 1.27)
				)
			)
		)
		(property "Value" ""
			(at 0 0 90)
			(layer "F.Fab")
			(effects
				(font
					(size 1.27 1.27)
				)
			)
		)
		(duplicate_pad_numbers_are_jumpers no)
		(fp_line
			(start 0.7874 -0.4064)
			(end 0.7874 0.4064)
			(stroke
				(width 0.1524)
				(type default)
			)
			(layer "F.SilkS")
		)
		(fp_line
			(start -0.7874 -0.4064)
			(end 0.7874 -0.4064)
			(stroke
				(width 0.1524)
				(type default)
			)
			(layer "F.SilkS")
		)
		(fp_line
			(start 0.7874 0.4064)
			(end -0.7874 0.4064)
			(stroke
				(width 0.1524)
				(type default)
			)
			(layer "F.SilkS")
		)
		(fp_line
			(start -0.7874 0.4064)
			(end -0.7874 -0.4064)
			(stroke
				(width 0.1524)
				(type default)
			)
			(layer "F.SilkS")
		)
		(fp_line
			(start -0.12065 -0.305054)
			(end -0.12065 -0.2794)
			(stroke
				(width 0.1)
				(type default)
			)
			(layer "F.Fab")
		)
		(fp_line
			(start -0.67945 -0.305054)
			(end -0.12065 -0.305054)
			(stroke
				(width 0.1)
				(type default)
			)
			(layer "F.Fab")
		)
		(fp_line
			(start 0.67945 -0.3048)
			(end 0.67945 0.3048)
			(stroke
				(width 0.1)
				(type default)
			)
			(layer "F.Fab")
		)
		(fp_line
			(start 0.12065 -0.3048)
			(end 0.67945 -0.3048)
			(stroke
				(width 0.1)
				(type default)
			)
			(layer "F.Fab")
		)
		(fp_line
			(start 0.12065 -0.2794)
			(end 0.12065 -0.3048)
			(stroke
				(width 0.1)
				(type default)
			)
			(layer "F.Fab")
		)
		(fp_line
			(start -0.12065 -0.2794)
			(end 0.12065 -0.2794)
			(stroke
				(width 0.1)
				(type default)
			)
			(layer "F.Fab")
		)
		(fp_line
			(start 0.120396 0.2794)
			(end -0.12065 0.2794)
			(stroke
				(width 0.1)
				(type default)
			)
			(layer "F.Fab")
		)
		(fp_line
			(start -0.12065 0.2794)
			(end -0.12065 0.3048)
			(stroke
				(width 0.1)
				(type default)
			)
			(layer "F.Fab")
		)
		(fp_line
			(start 0.67945 0.3048)
			(end 0.120396 0.3048)
			(stroke
				(width 0.1)
				(type default)
			)
			(layer "F.Fab")
		)
		(fp_line
			(start 0.120396 0.3048)
			(end 0.120396 0.2794)
			(stroke
				(width 0.1)
				(type default)
			)
			(layer "F.Fab")
		)
		(fp_line
			(start -0.12065 0.3048)
			(end -0.67945 0.3048)
			(stroke
				(width 0.1)
				(type default)
			)
			(layer "F.Fab")
		)
		(fp_line
			(start -0.67945 0.3048)
			(end -0.67945 -0.305054)
			(stroke
				(width 0.1)
				(type default)
			)
			(layer "F.Fab")
		)
		(pad "1" smd circle
			(at -0.40005 0 90)
			(size 0 0)
			(layers "F.Cu" "F.Mask" "F.Paste")
			(net "PVCCIN_CPU1_VDD7")
		)
		(pad "2" smd circle
			(at 0.40005 0 90)
			(size 0 0)
			(layers "F.Cu" "F.Mask" "F.Paste")
			(net "GND")
		)
	)
)
